M48
INCH,TZ
T01C.008
T02C.01
T03C.012
T04C.01456
T05C.016
T06C.02244
T07C.03
T08C.035
T09C.036
T10C.038
T11C.04
T12C.042
T13C.05
T14C.062
T15C.087
T16C.091
T17C.126
T18C.15
T19C.168
T20C.032
T21C.038
T22C.04
T23C.086
T24C.128
;LEADER: 12 
;HEADER: 
;CODE  : ASCII 
;FILE  : 15105-sa-1-8.drl for board 15105-sa.brd ... layers TOP and BOTTOM
;T01 Holesize 1. = 8.000000 Tolerance = +0.000000/-0.000000 PLATED MILS Quantity = 1618
;T02 Holesize 2. = 10.000000 Tolerance = +0.000000/-0.000000 PLATED MILS Quantity = 3185
;T03 Holesize 3. = 12.000000 Tolerance = +0.000000/-0.000000 PLATED MILS Quantity = 9
;T04 Holesize 4. = 14.560000 Tolerance = +0.000000/-0.000000 PLATED MILS Quantity = 288
;T05 Holesize 5. = 16.000000 Tolerance = +0.000000/-0.000000 PLATED MILS Quantity = 365
;T06 Holesize 6. = 22.440000 Tolerance = +0.000000/-0.000000 PLATED MILS Quantity = 36
;T07 Holesize 7. = 30.000000 Tolerance = +0.000000/-0.000000 PLATED MILS Quantity = 3
;T08 Holesize 8. = 35.000000 Tolerance = +0.000000/-0.000000 PLATED MILS Quantity = 14
;T09 Holesize 9. = 36.000000 Tolerance = +0.000000/-0.000000 PLATED MILS Quantity = 12
;T10 Holesize 10. = 38.000000 Tolerance = +0.000000/-0.000000 PLATED MILS Quantity = 4
;T11 Holesize 11. = 40.000000 Tolerance = +0.000000/-0.000000 PLATED MILS Quantity = 34
;T12 Holesize 12. = 42.000000 Tolerance = +0.000000/-0.000000 PLATED MILS Quantity = 3
;T13 Holesize 13. = 50.000000 Tolerance = +0.000000/-0.000000 PLATED MILS Quantity = 5
;T14 Holesize 14. = 62.000000 Tolerance = +0.000000/-0.000000 PLATED MILS Quantity = 2
;T15 Holesize 15. = 87.000000 Tolerance = +0.000000/-0.000000 PLATED MILS Quantity = 8
;T16 Holesize 16. = 91.000000 Tolerance = +0.000000/-0.000000 PLATED MILS Quantity = 2
;T17 Holesize 17. = 126.000000 Tolerance = +0.000000/-0.000000 PLATED MILS Quantity = 8
;T18 Holesize 18. = 150.000000 Tolerance = +0.000000/-0.000000 PLATED MILS Quantity = 3
;T19 Holesize 19. = 168.000000 Tolerance = +0.000000/-0.000000 PLATED MILS Quantity = 1
;T20 Holesize 20. = 32.000000 Tolerance = +0.000000/-0.000000 NON_PLATED MILS Quantity = 4
;T21 Holesize 21. = 38.000000 Tolerance = +0.000000/-0.000000 NON_PLATED MILS Quantity = 2
;T22 Holesize 22. = 40.000000 Tolerance = +0.000000/-0.000000 NON_PLATED MILS Quantity = 2
;T23 Holesize 23. = 86.000000 Tolerance = +0.000000/-0.000000 NON_PLATED MILS Quantity = 8
;T24 Holesize 24. = 128.000000 Tolerance = +0.000000/-0.000000 NON_PLATED MILS Quantity = 2
%
G90
T01
X118524Y491672
X118500Y504238
X115373Y504271
X115374Y529467
X118524
X118773Y589748
Y592048
X118771Y595196
X118773Y598345
X115623
X118773Y601495
X115622Y601496
Y604646
X118773Y604645
Y610945
X115622Y614094
X118805Y614099
X118771Y617244
X125072Y620392
X121921
X121922Y617244
X125070
X128221
X128220Y614095
X125070
X121911Y614076
X125072Y610945
X121922
X128221
X126646Y606400
X125070Y598347
X121922Y592048
Y588872
X126869Y577770
X121601Y574686
X126801Y574386
X122547Y567628
X124900Y565990
X122547Y564452
X124900Y562814
X122547Y561276
X124900Y559638
X122547Y558100
X124900Y556462
X122547Y554924
X124900Y553286
X122547Y551748
X124847Y550110
X124822Y545216
X121673Y545215
X127973Y542067
X124823
X124822Y538917
X121673Y538916
X127973Y538918
X124823Y535766
X121673
X127996Y535781
X124823Y532617
X127973Y532618
X121673Y532617
X124823Y529467
X127973Y529469
X121673Y529467
X127973Y523170
X124823
X121673
X124822Y520019
X121673Y520020
X127971Y520018
Y513721
X121673
X124821
X127973Y510571
X121673
X124823
X121673Y504272
X127973
X124822Y504271
X127973Y501122
X124823
X121673
X127973Y497973
X121673
X124823
X127971Y494823
X121673Y494822
X124823
X127973Y491674
X124823
X121673Y491672
X124822Y488523
X127973Y488524
Y485374
X122700Y478400
Y476100
X122600Y473800
Y471500
X134272Y485374
X137421
X131122
Y488524
X134272
X137421
X131122Y491674
X134272
X137421
X131121Y494823
X130985Y504300
X134270Y504272
X131121Y510570
X134270Y510571
X131121Y513721
X134270Y516869
X131121Y520018
Y523168
X134270Y523170
X131121Y529467
X134272Y532618
X137421
X131122
X134272Y535768
X137421
Y538918
X134270Y538916
X137421Y542066
X134272
X131369Y588898
X134521Y595196
X137670Y595197
X134521Y598345
X137669Y601495
X131370Y601496
X137669Y604645
X131369Y610945
X137669
X134520Y610944
X131369Y614095
X134519
X137661Y614096
X131369Y617244
X134521Y617266
X137671
X140821
X143969Y617244
X143968Y614095
X140821Y614106
X147141Y614096
X143967Y610945
X147117
X140818
X147117Y601495
X143968
X140818
X147115Y598360
X147143Y595184
X143968Y592048
Y588898
X147451Y556436
X142951Y555636
X147451Y554136
X142951Y553336
X147451Y551836
X142951Y551036
X147451Y549536
X143686Y542070
X143718Y538953
X146869Y538954
X140570Y535767
X146858Y535742
X140571Y532618
X143721
X140569Y529469
X146869
X146870Y516870
Y513721
Y510571
X140569Y494823
X146869
X140571Y491674
X143721
X146870
Y488524
X140570Y488523
X143721Y488524
X140571Y485374
X146870
X143721
X146870Y482225
X150020
X156319Y485374
X150020
X159469
X153169
X159469Y488524
X150020
X156318Y488523
X153169Y488524
X150020Y491674
X159469
X153170
X156319
X159467Y494823
X153168
X153169Y510571
X150020
X153169Y513721
X150020
Y516870
X153169
X159467Y529469
X153168
X153187Y532636
X159456Y532642
X153132Y535767
X149985Y535771
X153188Y538899
X159449Y538898
X149981Y538917
X159449Y542048
X153194Y542078
X159537Y548256
X151989Y552538
Y554838
Y557138
X159716Y592048
X153418
X159716Y595197
X153418
X159716Y598345
X150269Y598347
X159716Y601495
X150268Y601496
X159716Y604645
X150268Y610944
X159716Y610945
X153417
X156566
X150269Y614095
X156566
X153417
X159716
X150251Y617226
X159716Y617244
X153417
X156566
X150351Y620436
X162881Y617266
X162867Y614095
X162865Y610945
X166016Y610944
X162865Y604645
X166016Y601496
X162865Y601495
X166015Y598345
X162865Y595196
X161280Y566300
Y564000
Y561700
Y558400
Y556100
Y553800
X160700Y551356
X165766Y542066
X162617
X168916
X162617Y538916
X165766
X168916
Y535766
X162617
X162618Y532618
X168916Y523170
Y516870
Y510571
Y504272
X162618Y491674
X165768
X162618Y488524
X165768
X162618Y485374
X175217Y482225
X172067
X172065Y485374
X175215
X178365
X172065Y488524
X175216Y488523
X178365Y488524
X175215Y491674
X172065
X178365
Y494823
X175215
X172065
Y497973
X178365
X175215
X178365Y501122
X175215
X172065
X175216Y504271
X178365Y504272
X172065
X178365Y507422
X172065
X175215
X172065Y510571
X178365
X175215
X172065Y513721
X178365
X175215
X175216Y520019
X172065Y520020
X178365
X175215Y523170
X178365
X172065
X178365Y526319
X175215
X172065
Y529469
X175215
X178365
X175215Y532618
X178365
X172065
X178365Y535768
X175216Y535767
X172065Y535768
X175215Y538918
X172065
X181514Y520020
X184665Y520019
X184664Y516869
Y488522
X181514Y488524
X184664Y485372
X181514Y485374
Y479075
X878347Y261810
X874410Y257873
X878347
Y253936
X874410
Y249999
X878347
Y246062
X874410
X878347Y242125
X874410
Y238188
X878347
Y234251
X874410Y230314
X878347
Y226377
X874410Y222440
X878347
Y218503
X874410Y214566
X878347
Y210629
Y206692
X874410
Y202755
X878347
Y198818
X874410Y194881
X878347
Y190944
Y183071
X874410
X878347Y163386
X874410
X878347Y159449
Y155512
X874410
X878347Y151575
Y147638
X874410
X878347Y143701
Y139764
X874410
X878347Y135827
X874410Y131890
X878347
Y127953
X874410
X878347Y124016
X874410
X878347Y120079
X874410
X878347Y116142
X886221
Y120079
X882284
X882300Y124032
X886221Y124016
X882284Y127953
X886221
X882284Y131890
X886221
X882284Y135827
X886221
Y139764
X882284
X886221Y143701
X882284
Y147638
X886221
Y151575
X882284
X886221Y155512
X882284
X886221Y159449
X882284
Y163386
X886221
X882284Y167323
X886221Y171260
Y179134
Y183071
Y190944
X882284
X886221Y194881
X882284
Y198818
X886221
Y202755
X882284
Y206692
X886221
X882284Y210629
X886221
Y214566
X882284
Y218503
X886221
Y222440
X882284
X886221Y226377
X882284
X886221Y230314
X882284
X886221Y234251
X882284
Y238188
X886221
X882284Y242125
X886221
Y246062
X882284
Y249999
X886221
Y253936
X882284
Y257873
X886221
Y261810
X894095
X898032Y257873
X894095
X890158
Y253936
X894095
X898032
X894095Y249999
X898032
X890158
Y246062
X898032
X894095
X898032Y242125
X890158
X894095
X890158Y238188
X898032
X894095
Y234251
X898032
X890158
Y230314
X898032
X894095
X890158Y226377
X894095
X898032
Y222440
X894095
X890158
X894095Y218503
X898032
X890158
X898032Y214566
X890158
X894095
Y210629
X890158
X898032
X894095Y206692
X890158
X898032
X894095Y202755
X890158
X898032
Y198818
X890158
X894095
X898032Y194881
X890158
X894095
X898032Y190944
X890158
X894095
Y183071
X890158
X898032
X890158Y179134
X898032
X894095
X898032Y175197
X894095
X898032Y171260
X894095Y167323
X898032
X890158Y163386
X898032
X894095
Y159449
X898032
X890158
X898032Y155512
X890158
X894095
X898032Y151575
X890158
X894095
X890158Y147638
X898032
X894095
X898032Y143701
X890158
X894095
X890158Y139764
X898032
X894095
Y135827
X890158
X898032
Y131890
X890158
X894095
X890158Y127953
X898032
X894095
X898032Y124016
X894095
X890158
X894095Y120079
X890158
X898032
X894095Y116142
X905906
X901969
X905906Y120079
X909843
X901969
Y124016
X905906
X909843
Y127953
X901969
X905906
X909843Y131890
X905906
X901969
X905906Y135827
X901969
X909843
X901969Y139764
X909843
X905906
Y143701
X909843
X901969
Y147638
X909843
X905906
Y151575
X901969
Y155512
X905906
X909843
Y159449
X901969
X905906
X909843Y163386
X905906
X901969
X905906Y167323
X901969
X909843
Y171260
X905906
X901969
Y175197
X905906
X909843
Y179134
X901969
X905906
X901969Y183071
X905906
X909843
X901969Y190944
X909843
X905906
X901969Y194881
X905906
X909843
Y198818
X905906
X901969
X909843Y202755
X901969
X905906
X901969Y206692
X905906
X909843
X901969Y210629
X909843
X905906
Y214566
X901969
X909843
Y218503
X905906
X901969
Y222440
X905906
X909843
Y226377
X905906
X901969
X905906Y230314
X909843
X901969
X905906Y234251
X909843
X901969
Y238188
X905906
X909843
X901969Y242125
X909843
X905906
X909843Y246062
X905906
X901969
X905906Y249999
X909843
X901969
X905906Y253936
X901969
X909843
X901969Y257873
X905906
X909843
Y261810
X901969
X913780
Y257873
X917717
Y253936
X913780
X917717Y249999
X913780
X917717Y246062
X913780
X917717Y242125
X913780
X917717Y238188
X913780
Y234251
X917717
X913780Y230314
X917717
X913780Y226377
X917717
X913780Y222440
X917717
X913780Y218503
X917717
Y214566
X913780
Y210629
X917717
X913780Y206692
X917717
X913780Y202755
X917717
Y198818
X913780
X917717Y194881
X913780
Y190944
X917717
Y183071
X913780
X917717Y179134
X913780
X917717Y175197
X913780
Y171260
X917717
X913780Y167323
X917717
Y163386
X913780
X917717Y159449
X913780
Y155512
X917717
X913780Y151575
X917717
Y147638
X913780
X917717Y143701
X913780
Y139764
X917717
Y135827
X913780
Y131890
X917717
X913780Y127953
X917717
X913780Y124016
X917717
Y120079
X913780
Y116142
X921654
X929528
X921654Y120079
X929528
X925591
X929528Y124016
X925591
X921654
Y127953
X929528
X925591
X929528Y131890
X925591
X921654
X929528Y135827
X921654
X925591
X929528Y139764
X925591
X921654
X929528Y143701
X925591
Y147638
X921654
X929528
X921654Y151575
X925591
X929528
X921654Y155512
X925591
X929528
Y159449
X921654
X925591
Y163386
X929528
X921654
Y167323
X929528
X925591
Y171260
X921654
X929528
X921654Y175197
X929528
X925591
Y179134
X929528
X921654
X929528Y183071
X925591
X921654
X929528Y190944
X925591
X921654
X925591Y194881
X921654
X929528
Y198818
X925591
X921654
Y202755
X925591
X929528
Y206692
X925591
X921654
X929528Y210629
X921654
X925591
Y214566
X929528
X921654
X925591Y218503
X921654
X929528
X921654Y222440
X929528
X925591
Y226377
X921654
X929528
X921654Y230314
X925591
X929528
X921654Y234251
X929528
X925591
X929528Y238188
X925591
X921654
X925591Y242125
X929528
X921654
X929528Y246062
X925591
X921654
X929528Y249999
X925591
X921654
X929528Y253936
X925591
X921654
X929528Y257873
X925591
X921654
Y261810
X929528
X937402
X933465Y257873
X937402
Y253936
X933465
X937402Y249999
X933465
X937402Y246062
X933465
Y242125
X937402
Y238188
X933465
X937402Y234251
X933465
X937402Y230314
X933465
X937402Y226377
X933465
X937402Y222440
X933465
Y218503
X937402
X933465Y214566
X937402
Y210629
X933465
X937402Y206692
X933465
X937402Y202755
X933465
X937402Y198818
X933465
Y194881
X937402
Y190944
X933465
X937402Y183071
X933465
Y179134
X937402
Y175197
X933465
Y171260
X937402
X933465Y167323
X937402
X933465Y163386
X937402
X933465Y159449
X937402
Y155512
X933465
Y151575
X937402
X933465Y147638
X937402
Y143701
X933465
Y139764
X937402
X933465Y135827
X937402
X933465Y131890
X937402
X933465Y127953
X937402
Y124016
X933465
Y120079
X937402
Y116142
X941339
Y120079
Y124016
X949212Y127953
X941339
Y131890
Y135827
X949212Y139764
X941339
X949212Y143701
X941339
X949212Y147638
X941339
Y151575
X949212
X941339Y155512
X949212
Y159449
X941339
Y163386
X949212
Y167323
X941339
X949212Y171260
X941339
Y175197
X949212
X941339Y179134
X949212
Y183071
X941339Y190944
Y194881
X949212
Y198818
X941339
Y202755
X949212
Y206692
X941339
X949212Y210629
X941339Y214566
X949212
Y218503
X941339
Y222440
X949212
X941339Y226377
X949212
Y230314
X941339
Y234251
X949212
X941339Y238188
X949212
Y242125
X941339
Y246062
X949212
X941339Y249999
X949212
Y253936
X941339
X949212Y257873
X941339
X949212Y261810
X957086
X953149Y257873
X957086
Y253936
X953149
X957086Y249999
X953149
Y246062
X957086
Y242125
X953149
X957086Y238188
X953149
X957086Y234251
X953149
X957086Y230314
X953149
X957086Y226377
X953149
Y222440
X957086
Y218503
X953149
Y214566
X957086
X953149Y210629
X957086
Y206692
X953149
X957086Y202755
X953149
X957086Y198818
X953149
X957086Y194881
X953149
X957086Y190944
X953149
Y183071
X957086
X953149Y179134
X957086
X953149Y175197
X957086
X953149Y171260
X957086
X953149Y167323
X957086
Y163386
X953149
Y159449
X957086
Y155512
X953149
Y151575
X957086
Y147638
X953149Y143701
X957086
X953149Y139764
X957086
Y135827
X953149
X957086Y131890
X953149
Y127953
X957086
X953149Y124016
X957086
Y120079
X953149
Y116142
X957086
X964960
Y120079
X961023
X968897
X961023Y124016
X964960
X968897
X964960Y127953
X961023
X968897
X964960Y131890
X961023
X968897
X961023Y135827
X968897
X964960
Y139764
X961023
X968897
Y143701
X961023
X964960
X961023Y147638
X964960
X968897
X964960Y151575
X968897
X961023
Y155512
X964960
X968897
Y159449
X961023
X964960
Y163386
X961023
X968897
Y167323
X961023
X964960
Y171260
X968897
X961023
X968897Y175197
X961023
X964960
X961023Y179134
X964960
X968897
X964960Y183071
X961023
X968897
Y190944
X961023
X964960
X961023Y194881
X968897
X964960
Y198818
X961023
X968897
X964960Y202755
X968897
X961023
Y206692
X964960
X968897
X961023Y210629
X964960
X968897
X961023Y214566
X968897
X964960
X968897Y218503
X961023
X964960
Y222440
X968897
X961023
X964960Y226377
X961023
X968897
X961023Y230314
X964960
X968897
X961023Y234251
X968897
X964960
X968897Y238188
X961023
X964960
X961023Y242125
X968897
X964960
Y246062
X968897
X961023
Y249999
X968897
X964960
X968897Y253936
X961023
X964960
Y257873
X968897
X961023
X964960Y261810
X972834
X976771Y257873
X972834
Y253936
X976771
X972834Y249999
X976771
X972834Y246062
X976771
X972834Y242125
X976771
X972834Y238188
X976771
X972834Y234251
X976771
X972834Y230314
X976771
X972834Y226377
X976771
Y222440
X972834
X976771Y218503
X972834
Y214566
X976771
Y210629
X972834
Y206692
X976771
X972834Y202755
X976771
X972834Y198818
X976771
Y194881
X972834
Y190944
X976771
Y183071
X972834
Y179134
X976771
X972834Y175197
X976771
X972834Y171260
X976771
Y167323
X972834
Y163386
X976771
Y159449
X972834
X976771Y155512
X972834
X976771Y151575
X972834
X976771Y147638
X972834
Y143701
X976771
Y139764
X972834
X976771Y135827
X972834
X976771Y131890
X972834
Y127953
X976771
Y124016
X972834
X976771Y120079
X972834
Y116142
X988582
X980708
X984645Y120079
X988582
X980708
X984645Y124016
X988582
X980708
X988582Y127953
X980708
X984645
X988582Y131890
X984645
X980708
Y135827
X988582
X984645
X980708Y139764
X984645
X988582
X984645Y143701
X980708
X988582
X984645Y147638
X988582
X980708
X988582Y151575
X984645
X980708
Y155512
X984645
X980708Y159449
X988582
X980708Y163386
X984645
X988582
X984645Y167323
X980708
X988582
X984645Y171260
X980708
X988582
X984645Y175197
X980708
X988582
X984645Y179134
X988582
X980708
Y183071
X984645
X988582
X980708Y190944
X988582
X984645
X980708Y194881
X988582
X984645
X988582Y198818
X980708
X984645
X988582Y202755
X980708
X984645
X980708Y206692
X984645
X988582
X984645Y210629
X980708
X988582
Y214566
X984645
X980708
X984645Y218503
X980708
X988582
X984645Y222440
X988582
X980708
Y226377
X984645
X988582
Y230314
X984645
X980708
X984645Y234251
X980708
X988582
X980708Y238188
X984645
X988582
X984645Y242125
X988582
X980708
X988582Y246062
X980708
X984645
Y249999
X988582
X980708
X984645Y253936
X988582
X980708
X984645Y257873
X980708
X988582
X980708Y261810
X984645
X992519
X996456Y257873
X992519
Y253936
X996456
Y249999
X992519
X996456Y246062
X992519
Y242125
X996456
Y238188
X992519
X996456Y234251
X992519
X996456Y230314
X992519
Y226377
X996456
Y222440
X992519
X996456Y218503
X992519
Y214566
X996456
Y210629
X992519
Y206692
X996456
Y202755
X992519
X996456Y198818
X992519
Y194881
X996456
X992519Y190944
X996456
Y183071
X992519
X996456Y179134
X992519
Y175197
X996456
X992519Y171260
X996456
Y167323
X992519
Y163386
X996456
Y159449
X992519
X996456Y155512
Y151575
Y147638
Y143701
Y139764
X992519
X996456Y135827
Y131890
X992519Y127953
X996456
X992519Y124016
X996456
Y120079
X992519
Y115742
X1008267Y116142
X1000393
X1004330Y120079
X1000393
X1008267
X1004330Y124016
X1000393
X1008267
X1004330Y127953
X1000393
X1008267
Y131890
X1000393
X1004330
X1000393Y135827
X1004330
X1008267
X1000393Y139764
X1004330
X1008267
Y143701
X1000393
X1004330
X1008267Y147638
X1004330
X1000393
X1004330Y151575
X1008267
X1000393
Y155512
X1008267
X1004330
X1008267Y159449
X1004330
X1000393
X1008267Y163386
X1004330
X1000393
Y167323
X1008267
X1004330
X1008267Y171260
X1004330
X1000393
X1004330Y175197
X1000393
X1008267
X1004330Y179134
X1000393
X1008267
X1000393Y183071
X1004330
X1008267
X1004330Y190944
X1008267
X1000393
X1008267Y194881
X1000393
X1004330
X1008267Y198818
X1000393
X1004330
X1008267Y202755
X1000393
X1004330
X1008267Y206692
X1004330
X1000393
X1004330Y210629
X1000393
X1008267
X1004330Y214566
X1000393
X1008267
X1004330Y218503
X1008267
X1000393
X1004330Y222440
X1008267
X1000393
X1004330Y226377
X1008267
X1000393
X1008267Y230314
X1004330
X1000393
X1008267Y234251
X1004330
X1000393
X1004330Y238188
X1008267
X1000393
Y242125
X1004330
X1008267
X1000393Y246062
X1008267
X1004330
Y249999
X1008267
X1000393
X1008267Y253936
X1004330
X1000393
X1008267Y257873
X1004330
X1000393
Y261810
X1008267
X1016141
Y257873
X1012204
Y253936
X1016141
Y249999
X1012204
X1016141Y246062
X1012204
Y242125
X1016141
X1012204Y238188
X1016141
Y234251
X1012204
Y230314
X1016141
Y226377
X1012204
X1016141Y222440
X1012204
Y218503
X1016141
X1012204Y214566
X1016141
X1012204Y210629
X1016141
X1012204Y206692
X1016141
Y202755
X1012204
Y198818
X1016141
X1012204Y194881
X1016141
X1012204Y190944
X1016141
X1012204Y183071
X1016141
Y179134
X1012204
X1016141Y175197
X1012204
X1016141Y171260
X1012204
X1016141Y167323
X1012204
X1016141Y163386
X1012204
Y159449
X1016141
X1012204Y155512
X1016141
X1012204Y151575
X1016141
Y147638
X1012204
X1016141Y143701
X1012204
Y139764
X1016141
X1012204Y135827
X1016141
X1012204Y131890
X1016141
Y127953
X1012204
X1016141Y124016
X1012204
X1016141Y120079
X1012204
X1016141Y116142
X1021751Y117469
X1020078Y120079
X1023278
X1020078Y127953
Y131890
Y139764
Y147638
Y155512
Y163386
Y167323
Y175197
Y183071
Y194881
Y202755
Y206692
Y214566
Y222440
Y230314
Y238188
Y242125
Y246062
Y249999
Y253936
Y257873
T02
X489261Y-14185
X713461Y-3006
X728395Y-7315
X736308Y-7483
X746329Y-7789
X788408Y-4321
X790150Y-1400
X798061Y-6439
X883800Y-500
X1008353Y-1940
X1012177Y-2940
X1019859Y-7642
X1022711Y-4975
X1049261Y-14185
X1062044Y-4173
X1065620Y-4335
X1069200Y-4200
X1069261Y-14185
X1072800Y-800
X1089261Y-14185
X1303983Y22083
X1092094Y30362
X1084800Y9400
X1084000Y500
X1083500Y25500
X1083315Y36654
X1082974Y14467
X1082808Y30601
X1080672Y9500
X1076970Y30411
X1072804Y19894
X1072140Y16447
X1065700Y32888
X1065657Y28946
X1065700Y36088
X1064900Y10400
X1062470Y31823
X1062433Y37099
X1061253Y17487
X1061200Y24088
Y20888
X1061153Y27488
X1060800Y10100
X1056200
X1056049Y18396
X1052600Y14400
X1047429Y15229
X1046200Y24500
X1045850Y6228
X1044050Y28815
X1040218Y32140
X1040121Y26870
X1039822Y35743
X1033554Y30216
X1033017Y14743
X1030139Y30209
X1029553Y13981
X1025700Y7600
X1024330Y34379
X1022300Y13900
X1018900Y14198
X1010975Y29017
X1010229Y19022
X1007921Y39585
X1000985Y29307
X997385
X994650Y39880
X985579Y26494
X985403Y22993
X985315Y14425
X980100Y14500
X976500Y4500
X974100Y19600
X970064Y18764
X969100Y14600
X963700Y21700
X959877Y26978
X942500Y30100
X938000Y30300
X927250Y31450
X919400Y33300
X911800Y37000
X904262Y14894
X900250Y38150
X900200Y9600
X899769Y4355
X896500Y9500
X892745Y9681
X888474Y9173
X881700Y2300
X880883Y30583
X877500Y23600
X874300Y18875
X870600Y18915
X869447Y31024
X867600Y2500
X863300Y23575
X861000Y350
X859300Y9900
X858500Y28000
Y32000
Y36000
X858100Y21400
X857453Y303
X855489Y9811
X854252Y20800
X851100Y9100
X849051Y20908
X847000Y9100
X845052Y20800
X843500Y9150
X841652Y20800
X838252
X834500
X834227Y9000
X831592Y34411
X830773Y9000
X830500Y20800
X828283Y24734
X824462Y25770
X821877Y21090
X813900Y12900
X807514Y2199
X788550Y29350
X771715Y6840
X771600Y24200
X752763Y38638
X738384Y8232
X735186Y20714
X729555Y33100
X729132Y3575
X729000Y24800
X726155Y33095
X725314Y24751
X724018Y5719
X722955Y33095
X721890Y24887
X719555Y33100
X719008Y21999
X711919Y6754
X709120Y35980
X707051Y12174
X467669Y5500
X447669
X427669
X407669
X387669
X267669
X247669
X227669
X210028Y32605
Y12605
Y52605
Y72605
X226533Y72591
X228121Y63589
X228163Y78589
Y68589
X257731Y78589
X257759Y68589
X257851Y63589
X258159Y73589
X457700Y62300
X461900
X465127Y57727
X466000Y62300
X470200
X474400
X478400
X483250Y59480
X524000Y43500
X530400Y72400
X532400Y78200
X532500Y62900
X536100Y56700
X538800Y76900
X541200Y73400
X541600Y62600
X543000Y76300
X544500Y57400
X546800Y76200
Y46300
X566700Y48700
X570900Y56200
X573800Y72400
X575500Y78500
X575800Y63100
X579000Y72300
X579900Y55800
X580800Y76000
X584600Y63200
Y78200
X588000Y72200
Y57200
X590000Y46200
X614300Y55800
X616800Y72200
X619200Y62800
X619400Y77500
X620838Y58628
X622100Y72400
X624000Y76000
X624700Y61400
X628100Y77700
X628200Y62600
X631100Y72300
X631300Y57100
X634100Y46800
X653300Y48600
X656700Y57400
X661100Y73000
X662300Y63300
X662400Y78100
X665400Y72500
X665696Y57027
X667500Y76000
X671100Y63400
X671300Y78100
X674600Y72200
X676800Y46300
X720800Y78150
X721690Y53340
X723200Y42300
X723481Y76780
X726609Y46051
X726646Y42651
X726609Y49251
X727265Y52588
X730021Y42235
X732900Y44900
X741600Y41000
X742290Y68550
X747000Y44300
X748300Y53800
X750130Y63340
X755700Y79100
X759600Y79200
X762250Y44650
X772000Y64200
X775381Y66115
X778800Y66388
X782551Y67144
X786333Y66963
X791300Y74200
X806152Y51692
X808114Y67634
X809000Y76000
X820004Y44234
X823996Y44276
X828700Y48800
X831125Y67775
X832401Y46472
X847337Y46563
X848623Y70757
X851300Y45748
X851870Y52160
X852019Y70589
X855421Y70551
X858500Y40000
X858800Y52200
X858821Y70614
X859000Y43500
X859200Y47100
X868800Y49200
X871550Y56450
X875050Y56250
X878800Y49600
X883700Y50700
X883800Y41400
X887800Y40100
X894110Y49250
X895080Y52828
X900501Y48705
X905488Y54479
X907750Y51750
X909797Y55037
X912000Y45000
Y41000
X915486Y41030
X918952Y40680
X934881Y57322
X939064Y58104
X947900Y67900
X949102Y74964
X952500Y75100
X959300Y68600
Y72000
X959855Y61107
X964105Y62308
X967180Y66705
X990628Y49698
X992396Y45073
X997007Y49560
X1008508Y47704
X1011300Y53000
X1014700Y53700
X1017863Y45056
X1017908Y41556
X1024318Y51554
X1024432Y43718
X1033517Y48934
X1035783Y51473
X1036854Y47110
X1040241Y61043
X1047500Y41500
X1049470Y53749
X1049772Y57259
X1050875Y61090
X1051000Y41500
X1054090Y58470
X1054210Y53370
X1054835Y40386
X1057000Y57700
Y54500
X1057259Y77276
X1062088Y40597
X1068315Y56120
X1068390Y61611
X1071135Y57175
Y60375
X1074103Y44988
X1077432Y64225
X1078694Y43478
X1083379Y40889
X1088005Y46541
X1088287Y55917
X1096496Y51226
X1100992Y52374
X1103349Y70700
X1103253Y76910
X1103300Y73900
X1103424Y67690
X1105441Y54768
X1110664Y78483
X1122800Y55100
X1127300Y46300
X1131900Y70700
X1132100Y56300
X1140900Y71100
X1141900Y63300
X1142418Y78638
X1148900Y75900
X1149100Y46300
X1150700Y63300
X1151492Y78668
X1166500Y56200
X1171700Y45900
X1175100Y55700
X1175300Y71100
X1178100Y78000
X1183884Y61598
X1184100Y56100
X1185200Y72600
X1187100Y77900
X1188200Y61600
X1192300Y46100
X1193555Y61875
X1193900Y78000
X1210511Y52300
X1214700Y46000
X1215400Y57600
X1216300Y72900
X1218600Y56000
X1221200Y63400
X1221300Y78400
X1228000Y57000
X1228900Y72900
X1230000Y78800
X1230300Y63200
X1231400Y58300
X1235800Y46400
X1254500Y51100
X1258400Y45900
X1261900Y71039
X1265200Y77400
X1265500Y61900
X1269900Y61100
X1271300Y77100
X1272200Y57900
Y72900
X1275200Y61200
X1275800Y75900
X1279100Y46300
X1304000Y44000
Y67500
X1394500Y119626
X1304000Y90500
X1275500Y91000
X1273200Y103200
X1272700Y88000
X1270300Y91100
X1263200Y102700
X1262800Y93100
X1261900Y86000
X1256000Y103300
X1254200Y96300
X1232500Y90900
X1229900Y103100
X1229100Y87900
X1228300Y93100
X1220100Y102700
X1219500Y93300
X1219200Y87000
X1211500Y102900
X1194000Y93200
X1185800Y102900
X1185100Y93000
X1184800Y87200
X1177000Y102800
X1176200Y92900
X1175200Y85900
X1168400Y103000
X1143500Y93300
X1141200Y86800
X1134800Y93300
X1131880Y100377
X1131800Y85600
X1126400Y92200
X1123000Y99200
X1116933Y85243
X1114842Y83078
X1112700Y80700
X1061000Y111000
X1057000Y107700
X1053000Y109500
X1048100Y108500
X1044700
X1041300
X1037900
X1034500
X1030883Y108438
X1027483Y108431
X1024000Y108500
X1019900
X1015948
X956687Y85482
X956500Y108000
X953301Y85793
X949893Y106378
X949828Y109778
X949500Y97500
Y103000
X948200Y85900
X942800Y85700
X937642Y85562
X935000Y97400
X934438Y86700
X929800Y105900
X929213Y86593
X927100Y96900
X926093Y85239
X919050Y85500
X913979Y86580
X910000Y85300
X901899Y85942
X897600Y85500
X897000Y96700
X892900Y85300
X890000Y97800
X888600Y85700
X885042Y85292
X878394Y85780
X875001Y86003
X871696Y87082
X868800Y85300
X868200Y116000
X861300Y117800
X854400Y117500
X846702Y117371
X844900Y85100
X823551Y80551
X819000Y97100
X816043Y94981
Y99318
X810000Y109400
X797800Y104500
X781500Y85100
X776538Y107162
X769400Y111900
X765000Y112800
X753700Y102900
X753500Y110900
Y96600
X749800Y91400
X743490Y111940
X735326Y102660
X735157Y97005
X732500Y101621
Y98421
X723659Y97292
X723610Y106430
X723638Y118353
X723569Y100969
X723501Y82680
X723429Y91683
X723438Y112700
X720800Y81350
Y117350
Y102150
Y114150
Y96350
Y93150
Y105350
X678300Y93100
X674800Y86800
X674300Y102400
X669400Y93200
X665100Y102700
X664000Y91100
X660600Y93300
X659700Y86400
X656400Y102600
X631200Y87200
X628300Y103300
X628000Y93000
X624400Y91100
X621900Y87600
X619700Y92100
X619600Y103300
X618300Y88000
X615800Y91200
X611100Y103300
X588000Y87100
X585100Y103300
X584500Y93200
X580700Y90900
X579000Y87200
X576800Y91600
X576300Y103300
X574100Y87800
X572500Y91200
X566100Y103100
X544600Y87300
X541700Y92300
X540100Y102900
X537400Y91000
X535400Y87400
X532900Y92400
X531400Y102900
X531200Y87900
X528700Y91100
X522700Y102900
X479700Y90100
X455800Y110200
X454926Y118791
X452600Y114254
X264817Y105350
X264443Y109587
X260562Y85988
X259331Y118580
X258068Y110180
X258100Y93589
X258029Y97353
X257912Y101408
X257769Y83589
X228163Y93589
Y88589
X227989Y83589
X227606Y98642
X224576Y116678
X223641Y99302
X222354Y103006
X221418Y109634
X210028Y92605
X178577Y107902
X158577
X138577
X118577
X18577
X5500Y119571
Y159571
Y139571
X104000Y128330
X114364Y122054
X181738Y122711
X210478Y151203
X215136Y142786
X218299Y123319
X218725Y138175
X220300Y129300
X222356Y133438
X223750Y141370
X228007Y123787
X228500Y138100
X228708Y127115
X233500Y137000
X239600Y142900
X243000Y139000
X243500Y147500
X243618Y143381
X246500Y139000
X254000Y131500
X254500Y150250
Y146250
Y153750
Y157250
Y142750
X257422Y121792
X259500Y152000
Y143250
Y147750
Y156250
X264500Y142750
Y157250
Y146250
Y153750
Y150250
X274250Y133750
X275000Y147500
X280000Y153900
X284440Y139580
X285250Y133750
X285500Y130000
X286000Y143800
X286100Y153900
X290000Y141100
X290500Y152500
X292000Y130000
X294500Y152500
X352600Y132537
Y128200
X355069Y124122
X358917
X362528Y123931
X401200Y150200
X401300Y159800
Y153215
Y156715
X403600Y146042
Y142542
X406500Y146900
Y141700
X452500Y153300
X454871Y122291
X457400Y138900
X474990Y122660
X491466Y126683
X496782Y134315
X506006Y126183
X507861Y134154
X509369Y141559
X513876Y140964
X516100Y138871
X519300
X521465Y140964
X525000Y138400
X526977Y140708
X529176Y151713
X530177Y140708
X530800Y123900
X532110Y138400
X532560Y152046
X535960Y151999
X539031Y136200
X541600Y137769
X543900Y154800
X544800Y137769
X545500Y152200
X547400Y136170
X548700Y152200
X549100Y126900
X550300Y154800
X552800Y140800
X560633Y127988
X562603Y140881
X566531Y143123
X570754Y147365
X572990Y140501
X574450Y137780
X577650
X579200Y140400
X583640Y140636
X584650Y137800
X587850
X588955Y140600
X591377Y125797
X593000Y152800
X594150Y149950
X597350
X597846Y125623
X598240Y137800
X598300Y152850
X601250Y137780
X604450
X605924Y126398
X607520Y137780
X608089Y131519
X614721Y138287
X617000Y144500
X623498Y140671
X624626Y137880
X627826
X629393Y140451
X631940Y137800
X633900Y149600
X634950Y137880
X636950Y149650
X638150Y137880
X640150Y149650
X641159Y137800
X643160Y149600
X647000Y143000
X654500
X762400Y127600
X773900Y138300
X791200Y125300
X1122001Y126574
Y133324
Y130124
Y136874
X1135150Y137851
X1138700
X1141900
X1145450
X1154557Y138505
X1158107
X1161307
X1164857
X1170400Y144100
X1175851Y142410
X1178861Y142478
X1182061
X1184629Y137740
X1185070Y142384
X1187635Y137899
X1190835
X1193192Y142970
X1193845Y137855
X1196200Y142851
X1199400
X1200391Y156779
X1202410Y142850
X1203791Y156730
X1206991
X1210391
X1214795Y142443
X1219138Y137928
X1222148Y137960
X1225348
X1227999Y142465
X1228359Y137960
X1231009Y142463
X1234209
X1236692Y137720
X1237219Y142420
X1239700Y137851
X1242621Y153690
X1242900Y137851
X1245910Y137810
X1251801Y144871
X1252768Y141181
X1257899Y142881
X1258744Y145770
X1261944
X1262880Y142909
X1273068Y140514
X1273499Y151498
X1273520Y148070
X1274065Y137673
X1277265
X1278160Y140547
X1282189Y144361
X1283343Y141581
X1286543
X1287637Y144386
X1291660Y140257
X1292817Y137478
X1296017
X1297360Y140172
X1297668Y155524
X1301749Y125479
X1316590Y147210
X1317400Y143620
X1324845Y130527
X1325429Y148270
X1339471Y139268
X1340130Y145980
X1394500Y139626
Y159626
Y179626
Y199626
X1387196Y174160
X1385467Y180543
X1382138Y184129
X1381696Y173459
X1381568Y180579
X1368028Y175745
X1365804Y185197
X1359128Y167226
X1355321Y172119
X1354971Y167446
X1331243Y182198
X1311181Y186548
X1290870Y186285
X806665Y174050
X803265
X803169Y198850
X802200Y196000
X799000
X797890Y198918
X796089Y181182
X796051Y175147
X792760Y176043
Y180443
X792390Y199166
X792000Y195778
X787600Y195804
X786463Y199019
X778807Y179490
Y183890
X775397Y179165
Y184215
X773984Y189118
X771400Y185919
X770385Y189165
X768777Y171450
X766950Y189252
X766244Y185897
X765579Y169242
X763562Y189539
X761242Y169242
X751737Y194042
X748237
X697494Y186256
Y181919
X693300Y181200
X603000Y190710
X579811Y179500
X564483Y167935
X558121Y167249
X547173Y167987
X546800Y163450
X534000Y167400
X518686Y168200
Y163800
X515354Y168998
X515348Y163101
X512600Y186500
X507300Y175500
X505100Y164800
X503975Y172372
X498900Y171800
X498000Y194200
X494800Y162900
X480910Y164099
X480800Y160700
X456500Y169783
Y165418
X438561Y166892
X435161
X433400Y176800
X433000Y169700
X422876Y199830
X421757Y177999
X411400Y183900
X400400Y189100
X362300Y181900
Y176900
Y162400
Y171400
Y166900
X358300
Y171400
Y181900
Y176900
Y162400
X354800Y181900
Y176900
Y171400
Y166900
Y162400
X337000Y162000
X264397Y160977
X259500Y160750
X254500Y161250
X233537Y160630
X213282Y188452
X210484Y179525
X209866Y188492
X206297
X205013Y192596
X202892Y188441
X193400Y192900
X191800Y189600
X162500Y173500
X149380Y176010
X118500Y181000
Y176500
Y185000
Y188500
Y173000
X116000Y192000
Y196500
X111967Y199632
X108631Y168836
X104100Y194600
X100900Y173800
X96584Y195100
X78050Y196300
X26500Y199500
X22000Y167200
X21900Y199700
X21800Y188100
X5500Y199571
Y179571
Y219571
Y239571
X23100Y224500
X27300Y229000
X31400Y209190
X31500Y224400
X34900Y216800
X38050Y216728
X41250
X42800Y200100
X44400Y216600
X46760Y209157
X50200Y212000
X53400Y211928
X56600
X59800Y211800
X63250Y205050
X67600Y209500
X71000Y216600
X72934Y232675
X73600Y229289
X74200Y216528
X77400
X78000Y229289
X78508Y232693
X80600Y216700
X82676Y208785
X85600Y210800
X87978Y226596
X88276Y232700
X88259Y223184
X88800Y210851
X92000
X92659Y223184
X92859Y226659
X95200Y210800
X103100Y211600
X103700Y200800
X116000Y202000
Y207000
Y211500
X119800Y234531
X153000Y225000
X155026Y212580
X163000Y211500
X167000
X171500Y207500
Y202500
X172450Y211050
X183400Y221600
X196018Y204200
X214794Y212100
X236300Y227280
X241231Y238869
X244300Y226700
X247500Y233750
X266500Y239400
X271231Y237031
X277800Y208500
X279257Y226340
X283622
X307300Y221702
X307834Y237966
X383600Y203200
X410900Y217100
X422876Y204195
X455800Y208300
X517599Y229658
X531232Y229927
X539798Y228856
X539934Y232660
X540035Y236294
X541446Y222562
X546494Y216010
X554149Y200229
X561567Y205767
X576100Y234500
X582400Y209500
X587100Y234800
X587400Y238200
X587438Y230850
X588963Y227408
X592563Y228308
X596253Y210000
X597813Y220858
X597763Y239108
Y235108
Y231608
X602763Y232108
Y236608
X607700Y211800
X607763Y231608
Y235108
Y239108
X608800Y221400
X616718Y238408
X616970Y235017
X619363Y225108
X623363
X627363Y224358
X629663Y221708
X635190Y219641
X635482Y207733
X635863Y216308
X637300Y234500
X640400Y218200
X649400Y234500
X655500Y213500
X660700Y212000
X671124Y210770
X674500Y212000
X685115Y210677
X687900Y208100
X746037Y213992
X746237Y210392
X749337Y212192
X1126500Y222500
X1135750Y228750
X1150250
X1394500Y219626
Y239626
Y259626
Y279626
X1369300Y259300
X1368300Y267800
X1361500Y273500
X1358662Y275485
X1355066Y275228
X1352500Y267000
X1352000Y276700
X1348500Y276500
X1342000Y257500
Y265000
Y261500
Y268500
Y272500
Y254000
X1337000Y272000
Y254500
Y263250
Y267500
Y259000
X1332000Y265000
Y257500
Y268500
Y272500
Y261500
Y254000
X1322500Y266800
X1322000Y276500
X1312200Y275200
X1311200Y256500
X1308500Y262500
X1293500Y271000
X1290000
X1275500Y264500
X1226000Y261300
X1151000Y242000
X1147000
X1143000
X1028500Y257500
X983500Y279500
X982500Y271500
Y275500
X982000Y267500
X909000Y279000
X908500Y275000
Y270500
Y267000
X642463Y241608
X638963
X631063Y242108
X628563Y249108
X607763Y242608
Y250108
Y246108
X602763Y240858
Y249608
Y245108
X597763Y250108
Y242608
Y246108
X569500Y240225
X545974Y263240
X541637
X534481Y243676
X510462Y261315
X493186Y272414
X381700Y265800
X376600Y261350
X349970Y256720
X345820Y256570
X306900Y251000
X302500Y251600
X209200Y252800
X206200Y247500
X193303Y264310
X191000Y246500
X171100Y247500
X167600Y247600
X162910Y244290
X159662Y266600
X157400Y254000
X157300Y246500
Y259900
X157200Y241400
X155662Y266438
X134120Y267630
X127330Y248029
X112764Y264218
X112732Y272786
X109600Y276850
X107340Y266140
X101463Y268811
X97480Y266420
X94600Y277100
X94530Y264671
X93672Y270153
X89400Y279300
X77527Y255800
X75800Y274100
X71870Y257120
X68100Y255000
X63800Y267100
X63700Y257300
Y263925
Y260725
X60872Y274328
X58400Y271800
X57500Y263300
X55800Y266293
Y269493
X53100Y279500
X44900Y261750
X44426Y267408
X44029Y272572
X35150Y273250
X28400Y262800
X26600Y253582
Y249217
X18000Y271600
X5500Y279571
Y259571
Y319571
Y299571
X18000Y289400
X24000Y308700
X26300Y317600
X28200Y296100
X31700Y314700
X31662Y303262
X35150Y284350
X35300Y303100
X38800Y302900
X39000Y299500
X39600Y317600
X42900Y284500
X47355Y303376
X47800Y309400
X47912Y294940
X47991Y299958
X49934Y280811
X52050Y316100
X58383Y294947
X58700Y308600
X58730Y299508
X59173Y288186
X61800Y306900
X62200Y288256
X65400Y303800
Y288256
X65500Y291900
X68429Y288212
X71094Y285981
X71500Y297900
X73125Y288231
X75400Y309700
X76325Y288231
X77100Y303800
X77500Y291900
X77964Y285670
X84600Y303000
X95700Y293900
X96798Y301484
Y297915
X100500Y285300
X101630Y312236
X102499Y281183
X106400Y312200
X107213Y301192
X108500Y284000
X109810Y310358
X109972Y305968
X112217Y296435
X113915Y307600
X117484
X120700Y282400
X139286Y311214
X144595Y312861
X166087Y304350
X167700Y296882
Y292517
X170062Y304556
X180850Y285650
X222200Y300500
X230400Y283400
X245400Y296500
X267300Y300600
X269270Y315759
X269849Y308414
X277300Y304800
X282700Y300100
X287800Y311600
X297090Y311350
X299600Y297662
X303517Y309777
X306800Y290500
X307425Y309838
X310485Y314670
X311882Y310550
X312900Y290450
X313200Y299900
X321300Y301500
X328842Y300042
X328800Y315900
X331800Y309100
X334200Y299600
X341652Y301534
Y305034
X344955Y305843
X344958Y300740
X368900Y315700
X403900Y315492
X404040Y318900
X461389Y318510
X464086Y287614
X501867Y295490
X509143Y284391
X512100Y319700
X518277Y288680
X522409Y318441
X525881Y287776
X529881Y287376
X532499Y315591
X532921Y298436
X534481Y286876
X539481Y286676
X541681Y297976
X544993Y281352
X640532Y318099
X643932Y318104
X713000Y310000
X909500Y283000
X983500Y283500
X1255000Y317300
X1283300Y302900
X1288900Y304000
X1303700Y289500
X1309900Y292400
X1310500Y285500
X1314000Y286500
X1317026Y304858
X1322250Y282250
X1333500Y290500
X1355000Y286300
X1364000Y280500
X1394500Y319626
Y299626
Y339626
Y359626
X1299000Y347500
X1297500Y351800
X1293280Y345770
X1289960Y349900
X1282740Y350010
X1281900Y346580
X1277620Y349500
X1275060Y345690
X1272500Y350000
X1270500Y335500
X1266500
X1264820Y349320
X1258500Y335500
X1242000Y343000
X1213400Y355400
X1205500Y334400
X909500Y338000
X909000Y353600
X908700Y347300
X907500Y325000
X753000Y359000
X704500Y343000
X689500Y344000
X663140Y353982
X662897Y346873
X660244Y352200
Y349000
X652254Y336353
X648792Y358431
X646884Y355616
X643750Y321500
X643000Y343000
X640550Y321500
X639500Y342500
X636500Y356500
X635350Y320850
X633000Y353000
Y356600
X629500Y356500
X627500Y329900
X624101Y330010
X622629Y344635
X620000Y341500
X618680Y346780
X618600Y357100
X616706Y349718
X616640Y342230
X606322Y351522
X604170Y337900
X600800Y337400
X599100Y348700
X597600Y339100
X597500Y352050
X564100Y358100
X561781Y346281
X560531Y358080
X556500Y358000
X554400Y335900
X539507Y330787
X539450Y322166
X533779Y336979
X529126Y342336
X525347Y336979
X522209Y333841
X507809Y336341
X500198Y324041
X480532Y321332
X480000Y355800
X477037Y333841
X476600Y355800
X473637Y333876
X464086Y340500
X404170Y326708
X404040Y323300
X370700Y353900
X363270Y356940
X362825Y336000
X362500Y341700
X360820Y359299
X359403Y351203
X359132Y326647
X356953Y353653
X354505Y356102
X352003Y358603
X351515Y327915
X326041Y329282
Y325000
X316420Y331830
X315900Y320900
X315300Y344500
X310839Y344339
X302749Y332651
X301929Y351100
X297729Y351029
X295400Y325390
X287200Y326802
X283700Y322100
X267979Y342500
X267300Y328640
X260929Y345571
X257340Y338640
X248930Y358000
X248160Y343140
X221460Y335475
Y339875
X219580Y356970
X218102Y334880
X218070Y340244
X214776Y352807
X212536Y349805
X210177Y325381
X205840
X196529Y352284
X195940Y348814
X192407Y320262
X189365Y329905
X185970Y358962
X182969Y352641
X180571Y327023
X176674Y344934
X174943Y321015
X167687Y329434
X155891Y339730
X143000Y342900
X134800Y329600
X122000Y343300
X117700Y323400
X113000Y336000
X111900Y344200
X108484Y348377
X107558Y321012
X106717Y335600
X100277Y336077
X86511Y344200
X83500
X80300
X79455Y357174
X78121Y325870
X77421Y322470
X77290Y344212
X76055Y357145
X74221Y322470
X73721Y325870
X70591Y359309
X70210Y342700
X66800
X66400Y334500
X63500Y353960
X62400Y334500
Y342700
X58990
X58100Y334600
X55907Y350673
X54600Y328600
X54200Y347400
X52521Y350357
X51050Y321650
X49300Y346700
X49100Y328300
X48512Y356488
X43262Y357062
X38500Y321400
X34800Y321200
X24639Y321239
X21400Y341000
Y354000
Y327900
X5500Y339571
Y359571
Y379571
Y399571
X22900Y365300
X25350Y389000
X31500Y366900
X34153Y376916
X38518
X39300Y389557
X39866Y371366
X44866Y378634
X60610Y381665
X62838Y392392
X68365Y381464
X71794Y377639
X72708Y382055
X75256Y370303
X79600Y399200
X80940Y395989
X82500Y362890
X84700Y396000
X86904Y385798
X95223Y385704
X99128Y366961
X102000Y364700
X104204Y383661
X108200Y378656
X108453Y385164
X111950Y392050
X115951Y384138
X117300Y361700
X122645Y367966
X125600Y386700
X125718Y383302
X126800Y362500
X137862Y361723
X140500Y390500
X141216Y361163
X143000Y388000
X145027Y361163
X145500Y385500
X155657Y384291
X156573Y371799
X157550Y399100
X161311Y371428
X166321Y388316
X171434Y398093
X179381Y369903
X217000Y360000
X219018Y378000
X223383
X228100Y364600
X239100Y399200
X244000Y381982
Y377617
X258500Y391200
X267300Y362200
X288270Y365240
X294009Y363063
X297729Y362571
X301320Y362500
X310475Y364193
X313100Y374438
Y371038
X313875Y364201
X316205Y376006
X316315Y369889
X355872Y363965
X358362Y361649
X455450Y376050
X459200Y369300
X459450Y384050
X462700Y369300
X466700Y388800
X469700Y393300
X470200Y363800
X486700
X487000Y393300
X490200Y388800
X491860Y382140
X493700Y369300
X528850Y394750
X532978Y371023
X534500Y395100
X539400Y380781
Y376444
X550000Y381000
X552720Y364180
X559973Y387638
X561300Y369500
X561912Y390762
X573900Y360600
X576800Y369200
X581700Y360700
X589500Y361000
X603500Y371200
X609000Y390350
X609500Y360717
X617000Y382500
X621300Y366900
X623000Y382500
X626458Y372521
X629500Y371000
X633000Y360500
X639500Y371000
X643000Y369500
X653000Y380500
X676700Y378800
X680100Y378718
X683600
X687000Y378700
X743500Y362000
X897000Y370500
X902500Y370000
X907500Y368000
X1235400Y364400
X1249250Y390250
X1254000Y397000
X1257500
X1269500
X1273500
X1282000Y386500
X1282740Y383000
X1289500Y386500
X1290125Y382875
X1296500Y386500
X1297625Y382375
X1310068Y394084
X1311500Y391000
X1394500Y399626
Y379626
Y439626
Y419626
X1369700Y424600
X1273500Y400500
X1258000Y421500
X1201000Y417900
X1196600Y416200
X619100Y418000
X615500Y420100
X604400Y421200
X579900Y427400
X567150Y415750
X560900Y413700
X480368Y405606
X476531
X313500Y437400
X313300Y429603
X313294Y434006
X293800Y436100
X264100Y425400
X262900Y438700
X251700Y425200
Y421600
X249342Y439064
X238400Y416200
X235750Y419500
X217190Y428485
X212200Y428800
X212000Y438713
X205915Y422424
X205750Y408250
X200100Y415100
X197850Y437450
X197000Y404000
X192150Y406429
X185000Y419900
X177550Y407850
X158800Y406255
X153100Y439000
X152978Y435602
X150431Y420306
X146105Y403610
X142608Y403594
X137000Y436700
X136500Y417400
X131304Y418855
X131004Y422710
X129500Y412400
X127925Y428093
X126122Y432323
X124290Y401910
X120200Y436400
X116173Y422379
X113518Y420179
X110406Y417067
X107844Y414785
X107358Y409942
X105303Y419497
X103179Y423267
X103176Y434180
X100924Y409968
X99818Y437908
X96351Y438600
X92752Y434193
X92580Y410761
X85042Y439144
X79267Y410185
X79164Y426221
X77859Y429879
X72533Y416996
X57800Y420700
X48000Y422500
Y429500
Y426000
X43500Y418802
X35709Y426942
X31324Y410800
X21300Y429500
X20713Y418326
Y410087
X17500Y412374
X5500Y439571
Y419571
Y479571
Y459571
X23720Y472640
X31500Y447000
X33900Y469300
X36750Y462900
X45531Y474400
X46087Y455819
X46500Y460300
X47132Y444399
X47734Y465792
X49812Y479921
X53200Y462500
X64500Y459400
X64680Y452389
X64820Y455887
X70700Y443244
X73232Y476912
X85748Y475813
X89400Y470400
X89500Y466600
X91200Y448800
Y453200
X91311Y456609
X91370Y445394
X96351Y443000
X97100Y466500
X98400Y454400
X99749Y443671
X101200Y470400
X103500Y454700
X107900Y448900
X111500Y454700
X115500
X116235Y444665
X120000Y451285
X123696Y454452
X127820Y452280
X129520Y448660
X130633Y444763
X133000Y454700
X137000Y451300
Y454700
X137344Y446737
X139019Y443177
X143547Y477976
X145901Y441262
X146165Y444876
X149838Y446190
X159082Y452509
X159239Y449079
X159540Y445692
X163440Y453020
X166534Y450821
X173471Y454700
X175912Y450747
X176098Y444355
X177500Y454300
X186675Y453505
X189381Y451394
X193718
X196239Y462262
X197531Y451187
X201868
X205200Y442900
X216282Y463288
X216404Y469751
X217500Y441992
X219763Y472187
X220800Y446000
X220897Y441833
X227700Y476537
Y472200
X228900Y446800
X230572Y455128
X235850Y455050
X246300Y478600
X246375Y440725
X248500Y465000
X251800Y470100
X253302Y456679
X257400Y477300
X257493Y456679
X263700Y474600
X265100Y443300
X273783Y476100
X275900Y467300
X283400Y477900
X284200Y465000
X285800Y460810
X301162Y459290
X301170Y462780
X302140Y444160
X303440Y475360
X304293Y466146
X306521Y463576
X306612Y460177
X307400Y467600
X313500Y441000
X321900Y459800
X322036Y463198
X322268Y466591
X322305Y469991
X329014Y472022
X359500Y448800
X395100Y449100
X416100Y470800
X472600Y477700
X518100Y453200
X584500Y462500
X833900Y467000
X1012600Y476700
X1214100Y469800
X1259200Y471800
X1366000Y472900
X1394500Y479626
Y459626
Y519626
Y499626
X1291600Y495200
X812500Y499400
X644100Y488700
X520500Y519400
X487400Y492100
X380300Y508700
X342300Y511600
X335570Y491460
X333102Y485902
X330000Y501900
X327589Y504300
X327512Y509612
X305500Y483550
X304400Y511400
X303800Y505100
X303500Y491000
X291500Y497700
X290838Y501600
X286181Y498546
X286169Y502000
X285776Y489300
X282400Y487300
X280749Y512744
X275286Y504392
X272860Y489147
X269000Y504962
X265019Y497483
X264522Y511690
X260646Y499181
X260407Y502674
X257400Y481637
X257207Y502674
X256855Y499154
X256300Y486000
Y494500
Y490000
X255487Y512454
X250200Y506600
X246800Y496800
X246500Y493400
X246407Y488799
X246300Y482000
Y485400
X244100Y499900
X243200Y508000
X242800Y495486
X240450Y499400
X236737Y493170
X236100Y517100
X233290Y493277
X229200Y514800
X228347Y484700
X228298Y488100
X226530Y502307
X226300Y505700
X219800Y493700
X219700Y489800
X219300Y508700
X218906Y483186
X217800Y512500
X217500Y519800
X216873Y516458
X216600Y496550
X207026Y483956
X206700Y494000
Y498000
X203550Y484522
X203500Y499200
X202700Y495400
X200917Y490578
X89200Y518700
X88573Y503935
X77700Y502500
X77681Y499033
X77413Y506468
X76100Y483400
X75600Y518600
X70910Y502219
X67700Y518500
Y499120
X67162Y515142
X63519Y505320
X62298Y484200
X61870Y515670
X61128Y519646
X60987Y489223
X60900Y495122
X60150Y506450
X50140Y494559
Y490750
X35700Y488500
X5500Y519571
Y499571
Y559571
Y539571
X24800Y540900
X29300Y539850
X60300Y533900
X61800Y537000
X63000Y558930
X64200Y534500
X65381Y548719
X65600Y543200
X65800Y538900
X69100Y549200
X70000Y542500
X70800Y559895
X73700Y542600
Y549300
X73900Y527050
X74000Y557000
X74300Y533600
X74301Y538390
X77300Y531238
X77400Y559000
X77372Y526885
X77400Y550400
X77500Y554500
X77700Y538500
Y522500
X87608Y557685
X88204Y543283
X89200Y528500
X100140Y559260
X114400Y550000
X199900Y544500
X202300Y559763
X203300Y544500
X203304Y554684
X203300Y548500
Y538500
X205700Y559763
X206700Y548500
Y554500
Y538500
Y544500
X216300Y546350
Y550500
X216563Y555908
X217500Y529250
X219700Y550500
X221000Y541300
X225000
X229800Y558500
X234777Y550569
X239139Y525077
X239321Y521081
X249700Y525737
Y521250
X250100Y537100
X261100Y521250
X263300Y526300
X264500Y521309
X279994Y554794
X280200Y551400
X283600
X295876Y520800
X306900Y529100
X311406Y535944
X311500Y548000
X314900
X320500Y531000
X321000Y527000
X322700Y536500
X350000Y537600
X388900Y550400
X418900Y529300
X448200Y531400
X600400Y538000
X780800Y545900
X977500Y550000
X1006100Y528700
X1022600Y542100
X1237800Y524500
X1296400Y542400
X1363900Y537600
X1394500Y539626
Y559626
Y579626
Y599626
X1361800Y596800
X1294700Y593400
X1232300Y568900
X1017800Y572700
X957800Y570300
X743000Y598000
X527700Y587500
X500800Y567200
X443000Y596500
X401000Y575500
X372000Y579300
X301000Y588665
X300835Y578165
Y583165
X297750Y592750
X296200Y566900
X291000Y561450
X290000Y578165
X289835Y583165
Y588165
X288835Y593165
X269335
X269000Y589000
X257413Y590500
X255738Y574238
X253500Y590500
X252238Y574238
X248500Y583000
X222500Y573220
X222300Y577300
X218780Y560082
X216278Y567341
X216241Y563095
X216090Y593937
X198600Y588750
Y599750
X197500Y577300
X197334Y567232
X196782Y563564
X193001Y574708
X189500Y567700
X185500
Y577300
X184189Y564504
X181000Y595200
Y581500
Y585000
X104461Y571715
X104400Y590300
X102870Y561340
Y565740
X102000Y599000
X101750Y595600
X99460Y566200
X95252Y571638
X92000Y591200
X90500Y580100
Y587000
X87555Y561085
X87337Y569268
X87200Y565785
Y574250
X84226Y577924
X82000Y592500
X81000Y589000
Y579000
X80300Y596100
X77400Y577000
X77250Y562750
X71400Y578300
X69500Y586000
X55950Y572500
Y564500
X5500Y599571
Y579571
Y619571
Y639571
X62400Y624500
X62611Y608289
X63300Y634800
X66000Y604800
X69258Y603000
X78300Y637750
Y634250
X88000Y613600
X94860Y628750
X102000Y602500
X105851Y611436
X120351Y633500
X126851Y633449
X128220Y620392
X137551Y629849
X149851Y631251
X150280Y636620
X153019Y622720
X155851Y631051
X159716Y620392
X160851Y630651
X165851
X166015Y620392
X168769Y622720
X181371Y601636
X227500Y603500
X247717Y633233
X259300Y635900
Y639300
Y632400
X265850Y606400
X265900Y622400
X266100Y614400
X271500Y639500
X276300Y617350
X281700Y634900
X281800Y638900
X288400Y634200
Y626100
X292500Y630200
X322100Y638500
X347100Y605300
X357600Y638300
X386500Y607900
X410300Y637500
X724400Y626500
X953500Y607000
X956900
X960500
X1043300Y631300
X1045000Y617500
X1079500Y631000
X1300000Y637000
X1301000Y618500
X1394500Y619626
Y639626
Y679626
Y659626
X1358700Y655700
X1351500Y675000
X1345850Y676750
X1340000Y674000
X1334128
X1331000Y662000
X1327200Y661800
X1326128Y674000
X1317007Y664000
X1313607
X1310207
X1306128Y674000
X1302128Y674067
X1297617Y677117
X1297500Y664000
X1297400Y651300
X1290550
X1286800Y671100
X1265000Y672000
X1253500
X1081000Y670000
X1080000Y650500
X1047000Y644000
X1041900Y658100
X994248Y665818
X978898Y640169
X958898
X938898
X916319Y678588
Y658588
X639500Y678500
X309000Y679000
X305500Y676400
X281100Y651700
X260100Y647400
X256600Y652200
X250500Y642500
X238100Y643400
X236000Y656000
X206952Y655370
X201000Y674000
X175200Y678500
X171300Y678300
X164400Y668300
X162100Y677800
X150600Y648300
X150409Y643884
X150069Y640500
X136651Y653036
X131051Y656436
X125581Y641436
X119051Y653906
X116551Y644936
X109051Y645936
X94950Y677850
X54200Y666800
X53000Y645000
X47800Y666400
X43600Y665700
X43100Y670900
X39900Y678100
X36624Y669155
X35766Y673178
X34500Y666500
X33600Y675800
X29500Y676500
X26100Y671200
X24000Y659000
X5500Y659571
Y679571
Y699571
Y719571
X17500Y706300
X25050Y716900
X25200Y712650
X27125Y695275
X38000Y684000
X42130Y694440
X42100Y684000
X42300Y704900
X45800Y685100
X47300Y704400
X53500Y690200
X59100Y705600
X60650Y694050
X60700Y682100
X62000Y713000
X63300Y697200
X65350Y690356
X66700Y713500
X69700Y690300
X74500Y713400
X75450Y694150
X75800Y681900
X79250Y716050
X89825Y692875
X91450Y707650
X91800Y716100
X107000Y717800
X107950Y687650
X109800Y681900
X111400Y718300
X115000Y717600
X124150Y707050
X130900Y710800
Y714300
X137000Y715500
X142500Y709000
X150000Y701500
X160500Y689500
X164500Y693500
X167000Y686500
X167600Y715900
X171000
X178750Y712250
X182500Y705500
X185000Y684500
X186000Y705500
X189000Y684500
X193500Y700000
X199900Y692000
X203300
X210000Y700000
X215160Y718340
X217000Y705500
X219000Y694000
X231500Y699000
X241000Y712500
Y718000
X270556Y716702
X274406Y716598
X278406Y716531
X282406Y716598
X285500Y704900
X286406Y716531
X290338Y715800
X298406Y706000
X302406Y706031
X306406
X312500Y716500
X320000Y718200
X323600Y717800
X334800Y712000
X344200Y696300
X354300Y704500
Y696000
X360000Y704000
X363500
X367000
X370500Y705500
X586900Y713200
X608000Y700800
X627600Y685000
X657000Y714500
X668500Y700000
X678500Y684000
X847500Y717500
X851500Y705500
X852500Y718000
X864800Y707700
X868200
X916319Y698588
Y718588
X994248Y705818
Y685818
X1041500Y682000
X1067000Y711000
X1259000Y680000
X1278000Y689000
X1280500Y706000
X1285000Y694000
X1301728Y711200
Y714600
X1302000Y695500
X1302128Y685500
X1304500Y698000
X1307000Y686500
X1310376Y687205
X1312132Y684293
X1315000Y686500
X1315546Y709500
X1318500Y684667
X1321928Y683798
X1322439Y697767
X1323076Y686999
X1326758Y686678
X1329500Y684667
X1333500Y709500
X1336795Y685141
X1337500Y698000
X1338200Y689800
X1339934Y683832
X1341400Y686900
X1348500Y713000
X1394500Y719626
Y699626
Y739626
Y759626
X1377000Y725000
X1342000Y732500
X1340500Y742500
X1338128Y732872
X1337500Y723000
X1334128Y732667
X1333500Y723000
X1330128Y732667
X1326661Y740700
X1325600Y722987
X1315000Y723000
X1314628Y733000
X1310500Y723000
X1310100Y732900
X1306128Y732872
X1302128
X1294628Y733000
X1291428Y726117
X1062500Y738000
X1058500Y758000
X994248Y725818
Y745818
X916319Y758588
Y738588
X900999Y748550
X896500Y734000
X895800Y738400
X895278Y758885
X894465Y755501
X893400Y745100
X892100Y721100
X891056Y755641
X888400Y721400
X885400Y743600
X884778Y756198
X884700Y721100
X882227Y758835
X881200Y721300
X877000Y745000
X876036Y755481
X874887Y759253
X873367Y745335
X869562Y758457
X869406Y745531
X867410Y755824
X865406Y745598
X861406Y755198
Y745531
X858695Y759900
X857406Y745598
Y755198
X854049Y757573
X852895Y748648
X848000Y735500
X844500Y758000
X844000Y735500
X840500
X837000
X374275Y722919
X370875Y723000
X367675
X366792Y734171
X364354Y731801
X364275Y723033
X362091Y729538
X359500Y727335
X342900Y727200
X330000Y754000
X326000Y729000
X322178Y729178
X317300Y739300
X315132Y727197
X313452Y753856
X310016Y729793
X307278Y726198
X302000Y740800
X301310Y726403
X298620Y728596
X298500Y752000
X296132Y726171
X290720Y726333
X287278Y729031
X286500Y740500
X285333Y726241
X283161Y730092
X281500Y752000
Y748500
X275609Y726886
X272116Y755592
X270000Y732650
X269500Y736150
X268193Y755633
X266980Y723854
X262628Y744470
X258100Y726100
X241000Y721500
Y725500
X213500Y725000
X210300Y729500
X210000Y755500
X203300Y747500
Y741000
X199900
Y747500
X193500Y755500
X193000Y729500
X190000Y725000
X184700Y729400
X182860Y742240
X182750Y720250
X181200Y748900
X178000Y753400
X177700Y723900
X161200
X160700Y753400
X157700Y748900
X153700Y729400
X150450Y744150
X150200Y729400
X146450Y736150
X144400Y731600
Y728200
X136400Y721800
Y738300
X135700Y745200
X132200Y756300
X118060Y743460
X111400Y741800
X111300Y756000
X106900Y721300
Y738600
X95400Y731600
Y728200
X89800Y753400
X89400Y749200
X89300Y736300
X86900Y757900
X85800Y731000
Y727500
X68900Y730000
X68465Y736229
X59300Y734900
X56590Y720410
X54300Y734900
Y739900
Y729900
X49300Y734900
X27000Y754400
X21250Y742650
X21300Y728400
X21108Y732713
X18250Y749250
X5500Y739571
Y759571
Y799571
Y779571
X35000Y769900
X39000
X42800Y770000
X47800Y772900
X52500Y779600
X64900Y780500
X69800Y772700
X74300Y769950
X89400Y762400
X132200Y761300
X139250Y791250
X143000Y784500
X143250Y799250
X146500Y784500
X154000Y779000
X160400Y771000
X163800
X167600Y764900
X170500Y779000
X171000Y764900
X175660Y797340
X177500Y784500
X178750Y767750
X182500Y761000
X182750Y775750
X186000Y761000
X190000Y780500
X193000Y785000
X199900Y796500
X203300
X210300Y785000
X213500Y780500
X215160Y773840
X217000Y761000
X227409Y775903
X228550Y772700
X231750
X233000Y775903
X263181Y772181
X266906Y775531
X282378Y775431
X283500Y765631
X287115Y765584
X293692Y765571
X298400Y775700
X299184Y765691
X302700Y765400
X307406Y775198
X311200Y765500
X311406Y775198
X315406Y775200
Y765598
X469000Y784000
X478000Y777500
X480100Y784575
X482925Y777422
X483000Y788150
X483500Y784650
X483850Y773800
X487906Y768598
X489522Y780127
X491906Y768531
X495906Y768598
X496061Y781678
X497910Y778824
X499000Y793000
X499906Y768531
X500778Y781031
X503906Y768598
X504278Y779198
X507729Y778198
X507906Y768531
X511484Y778515
X511800Y768300
X515000Y792500
X515278Y779198
X515650Y764500
X515900Y768300
X519748Y768297
X519906Y764900
X522500Y782031
X524795Y778529
X528179Y782555
X531500Y774500
X531600Y770200
X532000Y792500
X535178Y781000
X540500
Y761000
X544000
X547395Y761198
X645800Y780500
Y776900
Y783900
X648900Y782500
X839990Y789230
X841500Y771000
X844150Y762150
X846706Y797648
X851890Y789270
X853500Y798000
X855500Y775500
X858126Y763600
X866878Y794531
X870278
X871000Y776500
X874000Y772000
X877930Y796880
X882290Y796770
X884671Y775500
X886288Y794372
X889900Y769600
X894200Y794500
X898700Y794200
X900824Y781531
X916319Y778588
Y798588
X994248Y765818
Y785818
X1394500Y799626
Y779626
Y819626
X1389925Y835051
X1378000Y806900
X1369925Y835051
X1351760Y827374
X1350025Y830301
X1346825
X1345088Y827374
X1339162
X1337427Y830301
X1334227
X1332490Y827374
X1326564
X1324829Y830301
X1321629
X1319892Y827374
X1313966
X1312231Y830301
X1309031
X1307294Y827374
X1304800Y811900
X1288768Y827374
X1287033Y830301
X1283833
X1282096Y827374
X1276170
X1274435Y830301
X1271235
X1269498Y827374
X1263572
X1261837Y830301
X1258637
X1256900Y827374
X1250974
X1249239Y830301
X1246039
X1244302Y827374
X1238375
X1236640Y830301
X1233440
X1231703Y827374
X1225777
X1224042Y830301
X1220842
X1219105Y827374
X1194280
X1192545Y830301
X1189345
X1187608Y827374
X1181682
X1179947Y830301
X1176747
X1175010Y827374
X1174900Y818300
X1161700Y818500
X1159634Y827374
X1157899Y830301
X1154699
X1152962Y827374
X1147036
X1145301Y830301
X1142101
X1140364Y827374
X1134438
X1132703Y830301
X1129503
X1127766Y827374
X1121839
X1120104Y830301
X1116904
X1115167Y827374
X1109241
X1107506Y830301
X1104306
X1102569Y827374
X1096642
X1094907Y830301
X1091707
X1089970Y827374
X1084044
X1082309Y830301
X1079109
X1077372Y827374
X1071446
X1069711Y830301
X1066511
X1064774Y827374
X1058847
X1057112Y830301
X1053912
X1052175Y827374
X1046249
X1044514Y830301
X1041314
X1039577Y827374
X994248Y805818
X916319Y818588
X906396Y810300
X906450Y806900
X906092Y813687
X898700Y816000
X894406Y818000
X890200Y819200
X888100Y823338
X885167Y816593
X884412Y835051
X881720Y807390
X876470Y808710
X874570Y811820
X870900Y812104
X865378Y804431
X861406Y804403
X857406
X855697Y827374
X853962Y830301
X850762
X849906Y804531
X849025Y827374
X843099
X841364Y830301
X838164
X836427Y827374
X817902
X816167Y830301
X812967
X811230Y827374
X805304
X803569Y830301
X800369
X798632Y827374
X792705
X790970Y830301
X787770
X786033Y827374
X780107
X778372Y830301
X775172
X773435Y827374
X767509
X765774Y830301
X762574
X760837Y827374
X754910
X753175Y830301
X749975
X748238Y827374
X742312
X740577Y830301
X737377
X735640Y827374
X729713
X727978Y830301
X724778
X723041Y827374
X714900Y818600
X712495Y816195
X698217Y827374
X698100Y821600
X696482Y830301
X693282
X691545Y827374
X685619
X683884Y830301
X680684
X678947Y827374
X673020
X671285Y830301
X668085
X666348Y827374
X660422
X658687Y830301
X655487
X653750Y827374
X653500Y819100
X638375Y827374
X636640Y830301
X633440
X631703Y827374
X625777
X624042Y830301
X620842
X619105Y827374
X613178
X611443Y830301
X608243
X606506Y827374
X600580
X598845Y830301
X595645
X593908Y827374
X587981
X586246Y830301
X583046
X581309Y827374
X575383
X573648Y830301
X570448
X568711Y827374
X562785
X561050Y830301
X557850
X556113Y827374
X550186
X548451Y830301
X545251
X543514Y827374
X542500Y806000
X533800Y835500
X528906Y817598
X527500Y836200
X526274Y806000
X524700Y817500
X516943Y817401
X512679Y827500
X512716Y817550
X511500Y803000
X508579Y827421
X507044Y817569
X500807Y831499
X500700Y828100
X500415Y817532
X497000Y817500
X496335Y835051
X495878Y827431
X494582Y800500
Y804000
X491906Y827403
X487906
X485300Y808250
Y811750
X480406Y827531
X477206Y820648
X461300Y813100
X457900
X456335Y835051
X428926Y827374
X427191Y830301
X423991
X422254Y827374
X416328
X414593Y830301
X411393
X409656Y827374
X403729
X401994Y830301
X398794
X397057Y827374
X391131
X389396Y830301
X386196
X384459Y827374
X369083
X367348Y830301
X364148
X362411Y827374
X356485
X354750Y830301
X351550
X349813Y827374
X343886
X342151Y830301
X338951
X337214Y827374
X331288
X329553Y830301
X326353
X324616Y827374
X318689
X316954Y830301
X313754
X312017Y827374
X280894
X279159Y830301
X275959
X274222Y827374
X268296
X266561Y830301
X263361
X261624Y827374
X255697
X253962Y830301
X250762
X249025Y827374
X233650
X231915Y830301
X228715
X226978Y827374
X221052
X219317Y830301
X216117
X214380Y827374
X208700Y828000
X206718Y830301
X203518
X203124Y824090
X201641Y827947
X200620Y821701
X197420
X196474Y832178
X195000Y824090
X194120Y830301
X190920
X188572Y832186
X174000Y804000
X170800Y808500
X163800Y820000
X160400
X153500Y808500
X150500Y804000
X145900Y824400
X141100Y824500
X141000Y830700
X138500Y835000
X137600Y839500
X115500Y825500
X109900Y828800
X107600Y825500
X105400Y828700
X103200Y825400
X93300Y818900
X93100Y813200
X90020Y835051
X70020
X50020
X30020
X10020
X5500Y819571
X117500Y878200
X120000Y865000
Y853500
Y843500
Y875000
X122000Y878200
X124500Y875000
X126500Y871000
Y878200
X129000Y875000
X138500Y869500
Y875200
X141000Y877700
X142500Y856500
Y872500
Y867500
Y862500
X145500Y877700
X149700
X159449Y878276
X168898Y878200
X173500Y867600
X176771Y878276
X176900Y867600
X185500Y878200
X195669Y878276
X196000Y868700
X197218Y871676
X200418
X201500Y868700
X201969Y878276
X208267
X209817Y875176
X213017
X214567Y878276
X220866
X222415Y875176
X225615
X227166Y878276
X233464
X235013Y875176
X238213
X239764Y878276
X249212
X255511
X257061Y875176
X260261
X261811Y878276
X268110
X269659Y875176
X272859
X274410Y878276
X280708
X280800Y863500
X282300Y866200
X285500
X286800Y863300
X287008Y878276
X306500Y868700
X307755Y865676
X310955
X312000Y868600
X312500Y878200
X318503Y878276
X320053Y875176
X323253
X324803Y878276
X331102
X332651Y875176
X335851
X337402Y878276
X343700
X345250Y875176
X348450
X350000Y878276
X356299
X357848Y875176
X361048
X362599Y878276
X370500Y878200
X378346Y878276
X379896Y875176
X383096
X384646Y878276
X390944
X392494Y875176
X395694
X397244Y878276
X403543
X405092Y875176
X408292
X409843Y878276
X416141
X417691Y875176
X420891
X422441Y878276
X431889
X438189
X444500Y864450
X527941Y864680
X538000Y878200
X538951Y875176
X542151
X544000Y878200
X550000Y878276
X551550Y875176
X554750
X556300Y878276
X562598
X564148Y875176
X567348
X568898Y878276
X575197
X576747Y875176
X579947
X581497Y878276
X587795
X589345Y875176
X592545
X594095Y878276
X600393
X601944Y875176
X605144
X606693Y878276
X612992
X614542Y875176
X617742
X619292Y878276
X625590
X627140Y875176
X630340
X631890Y878276
X642200Y877900
X647838Y872000
X649188Y875176
X652388
X654000Y878200
X660236Y878276
X661786Y875176
X664986
X666536Y878276
X672834
X674385Y875176
X677585
X679134Y878276
X685433
X686983Y875176
X690183
X691733Y878276
X697700Y866100
X698031Y878276
X699200Y868800
X702400
X703900Y866100
X704331Y878276
X723000Y878200
X729527Y878276
X731077Y875176
X734277
X735827Y878276
X742126
X743676Y875176
X746876
X748426Y878276
X754724
X756274Y875176
X759474
X761024Y878276
X767323
X768873Y875176
X772073
X773623Y878276
X779921
X781471Y875176
X784671
X786221Y878276
X792519
X794070Y875176
X797270
X798819Y878276
X805118
X806668Y875176
X809868
X811418Y878276
X820000Y878200
X830315Y878276
X831865Y875176
X835065
X836615Y878276
X842913
X844463Y875176
X847663
X849213Y878276
X856000Y878200
X861823Y853696
X1024004Y855893
X1033464Y878276
X1035014Y875176
X1038214
X1039764Y878276
X1046063
X1047613Y875176
X1050813
X1052363Y878276
X1058661
X1064961
X1071260
X1072810Y875176
X1076010
X1077560Y878276
X1083858
X1085408Y875176
X1088608
X1090158Y878276
X1096456
X1098007Y875176
X1101207
X1102756Y878276
X1109055
X1110605Y875176
X1113805
X1115355Y878276
X1121653
X1123203Y875176
X1126403
X1127953Y878276
X1134252
X1135802Y875176
X1139002
X1140552Y878276
X1146850
X1148400Y875176
X1151600
X1153150Y878276
X1159448
X1160999Y875176
X1164199
X1165748Y878276
X1173623Y878200
X1181496Y878276
X1183046Y875176
X1186246
X1187796Y878276
X1194063Y864273
X1194094Y878276
X1195800Y867300
X1199000Y867200
X1200394Y878276
X1200735Y864273
X1217717Y878076
X1225590Y878276
X1227140Y875176
X1230340
X1231890Y878276
X1238189
X1239739Y875176
X1242939
X1244489Y878276
X1250787
X1252337Y875176
X1255537
X1257087Y878276
X1263386
X1264936Y875176
X1268136
X1269686Y878276
X1275984
X1277534Y875176
X1280734
X1282284Y878276
X1288582
X1290133Y875176
X1293333
X1294268Y872169
X1301800Y878100
X1302731Y875176
X1305931
X1307481Y878276
X1313779
X1315329Y875176
X1318529
X1320079Y878276
X1326378
X1327928Y875176
X1331128
X1332678Y878276
X1338976
X1340526Y875176
X1343726
X1345276Y878276
X1352200Y878400
X1357886Y864246
T03
X113300Y276600
X113000Y280500
X113100Y284100
X125100Y282500
X131700Y275700
Y280000
X294000Y716000
X300500Y715613
X528100Y767300
T04
X527104Y49331
X524151Y54843
X527104Y64292
X524151Y69803
X527104Y79252
X524151Y84764
X527104Y94213
X524151Y99725
X533010
X538915Y96969
X530057
X535962Y94213
X533010Y84764
X530057Y82008
X538915
X535962Y79252
X533010Y69803
X538915Y67048
X530057
X535962Y64292
X533010Y54843
X530057Y52087
X538915
X535962Y49331
X544821
X547773Y52087
X541868Y54843
X544821Y64292
X547773Y67048
X541868Y69803
X544821Y79252
X547773Y82008
X541868Y84764
X544821Y94213
X547773Y96969
X541868Y99725
X567458
Y84764
Y69803
Y54843
X570411Y49331
X579269
X573364Y52087
X576317Y54843
X570411Y64292
X579269
X573364Y67048
X576317Y69803
X570411Y79252
X579269
X573364Y82008
X576317Y84764
X570411Y94213
X579269
X573364Y96969
X576317Y99725
X585175
X582222Y96969
X588128Y94213
X585175Y84764
X582222Y82008
X588128Y79252
X585175Y69803
X582222Y67048
X588128Y64292
X585175Y54843
X582222Y52087
X588128Y49331
X591080Y52087
Y67048
Y82008
Y96969
X610766Y99725
X619624
X616671Y96969
X613718Y94213
X610766Y84764
X619624
X616671Y82008
X613718Y79252
X619624Y69803
X610766
X616671Y67048
X613718Y64292
X610766Y54843
X619624
X616671Y52087
X613718Y49331
X622577
X625529Y52087
X628482Y54843
X622577Y64292
X625529Y67048
X628482Y69803
X622577Y79252
X625529Y82008
X628482Y84764
X622577Y94213
X625529Y96969
X628482Y99725
X634388Y96969
X631435Y94213
X634388Y82008
X631435Y79252
X634388Y67048
X631435Y64292
X634388Y52087
X631435Y49331
X657025
X654073Y54843
X657025Y64292
X654073Y69803
X657025Y79252
X654073Y84764
X657025Y94213
X654073Y99725
X662931
X659978Y96969
X668836
X665884Y94213
X662931Y84764
X659978Y82008
X668836
X665884Y79252
X662931Y69803
X668836Y67048
X659978
X665884Y64292
X662931Y54843
X668836Y52087
X659978
X665884Y49331
X674742
X677695Y52087
X671789Y54843
X674742Y64292
X677695Y67048
X671789Y69803
X674742Y79252
X677695Y82008
X671789Y84764
X674742Y94213
X677695Y96969
X671789Y99725
X1126513
X1129466Y94213
X1126513Y84764
X1129466Y79252
X1126513Y69803
X1129466Y64292
X1126513Y54843
X1129466Y49331
X1138324
X1132419Y52087
X1135372Y54843
X1138324Y64292
X1132419Y67048
X1135372Y69803
X1138324Y79252
X1132419Y82008
X1135372Y84764
X1138324Y94213
X1132419Y96969
X1135372Y99725
X1144230
X1141277Y96969
X1147183Y94213
X1144230Y84764
X1141277Y82008
X1147183Y79252
X1144230Y69803
X1141277Y67048
X1147183Y64292
X1144230Y54843
X1141277Y52087
X1147183Y49331
X1150135Y52087
Y67048
Y82008
Y96969
X1169820Y99725
Y84764
Y69803
Y54843
X1172773Y49331
X1175726Y52087
X1178679Y54843
X1172773Y64292
X1175726Y67048
X1178679Y69803
X1172773Y79252
X1175726Y82008
X1178679Y84764
X1172773Y94213
X1175726Y96969
X1178679Y99725
X1187537
X1184584Y96969
X1181631Y94213
X1187537Y84764
X1184584Y82008
X1181631Y79252
X1187537Y69803
X1184584Y67048
X1181631Y64292
X1187537Y54843
X1184584Y52087
X1181631Y49331
X1190490
X1193442Y52087
X1190490Y64292
X1193442Y67048
X1190490Y79252
X1193442Y82008
X1190490Y94213
X1193442Y96969
X1213128Y99725
X1219033Y96969
X1216080Y94213
X1213128Y84764
X1219033Y82008
X1216080Y79252
X1213128Y69803
X1219033Y67048
X1216080Y64292
X1213128Y54843
X1219033Y52087
X1216080Y49331
X1224939
X1227891Y52087
X1221986Y54843
X1224939Y64292
X1227891Y67048
X1221986Y69803
X1224939Y79252
X1227891Y82008
X1221986Y84764
X1224939Y94213
X1227891Y96969
X1221986Y99725
X1230844
X1236750Y96969
X1233797Y94213
X1230844Y84764
X1236750Y82008
X1233797Y79252
X1230844Y69803
X1236750Y67048
X1233797Y64292
X1230844Y54843
X1236750Y52087
X1233797Y49331
X1259387
X1256435Y54843
X1259387Y64292
X1256435Y69803
X1259387Y79252
X1256435Y84764
X1259387Y94213
X1256435Y99725
X1265293
X1262340Y96969
X1268246Y94213
X1265293Y84764
X1262340Y82008
X1268246Y79252
X1265293Y69803
X1262340Y67048
X1268246Y64292
X1265293Y54843
X1262340Y52087
X1268246Y49331
X1277104
X1271198Y52087
X1274151Y54843
X1277104Y64292
X1271198Y67048
X1274151Y69803
X1277104Y79252
X1271198Y82008
X1274151Y84764
X1277104Y94213
X1271198Y96969
X1274151Y99725
X1280057Y96969
Y82008
Y67048
Y52087
T05
X103700Y775800
X108200
X112700Y775300
X108200Y770800
X112700
X103700
X112700Y766300
X103700
X108200
X156170Y318302
X153670Y314302
X158170
X160670Y318302
X162670Y314302
X224500Y166300
Y170500
Y174700
Y178900
X223000Y184000
Y188500
X229200Y192500
X225000
X239900Y600100
X240000Y608600
Y604400
X258225Y193963
X243000Y186000
Y181000
Y176500
X258700Y166500
X243500
X253000
X243500Y162000
Y157000
X259500Y138500
X262900Y166500
X261500Y173500
Y179000
X271000Y184500
X261500
X266500
X261000Y190500
X266500
X339500Y192500
X329500
X334500
X328000Y197400
X334500Y197500
X339500
X344000
Y192500
X536809Y298789
X536081Y304376
X553563Y306108
Y310608
X553455Y314807
X553463Y319108
X557863
X557904Y327115
X562123Y319158
X560318Y295699
X560418Y289299
Y283799
Y278299
X560318Y272199
Y267199
X565063Y256608
Y252108
Y247608
X582976Y246148
X587984
X587980Y251975
X583286Y251974
X582682Y257614
X587063Y257608
X583009Y264117
X589164Y264150
X585351Y269292
X582738Y273300
X585515Y276459
X582683Y279618
X585737Y283108
X582411Y286589
X585737Y289608
X582363Y293408
X583391Y298870
X583282Y303091
X589400Y308626
X580563Y308608
X607519Y299497
X607563Y293608
X611563Y290108
X607563Y287608
X611563Y284608
X607563Y282108
X611563Y278108
X607563Y276108
X607463Y270608
X607563Y265608
Y261108
X605063Y257608
X609063Y255608
X658093Y223677
X672927Y219677
X677927
X662593Y223677
X666593Y226677
X678063Y238108
X673063
X669633Y259148
X674133
X674563Y274708
X679723Y274748
X670063Y274708
X672100Y299800
X677000Y299900
X695963Y302308
X682063Y299108
X695963Y297808
X683800Y295000
X695963Y293308
X690663Y292108
X684063Y290408
X690663Y287608
X684063Y285908
X689723Y274748
X684223
X694223
X694963Y269608
X689623Y269648
X690133Y260348
X694633
X684633Y259148
X680133
X695000Y255800
X690233Y255748
X682763Y238008
X687253Y237878
X691753
X696800Y237900
X686063Y230108
X698300Y226500
X693800
X686063Y224608
X712337Y207792
X712137Y213292
Y219392
X704537Y221492
X716300Y228700
X711300
X703600Y233700
X716900Y233800
X712400
X707900
X715300Y251500
X706800Y252000
X715300Y258000
X706800
Y265500
X715300
Y272000
X706800Y272500
Y290700
X718800Y291000
X714300
X718863Y295908
X714363
X707363Y298108
X732363Y295908
X727863
X723363
X732300Y291000
X737300
X727800
X723300
X732300Y272000
X724300
X738800
Y265500
X732300
X724300
Y258000
X732300
X738800
Y251500
X732300
X724300
X725900Y233800
X735400
X730400
X721400
X730300Y228700
X725300
X918100Y71900
X921300Y74700
X926500Y60050
X930500Y57500
X929464Y49420
X929713Y44849
X925022Y42909
X975086Y61900
X970000Y61050
X971466Y26681
X976066Y26581
X980566
X985880Y41686
Y46086
Y50586
X1171300Y215700
X1166300
X1175999
X1175700Y234300
X1179900
X1170600
X1166400
X1173400Y241200
X1177600
X1177200Y248200
X1173000
X1173100Y254400
X1177300
X1176300Y261500
X1171200
X1167000
X1173000Y280000
X1177500
X1168000
X1196200
X1192000
X1182500
X1187000
X1194300Y261500
X1189500
X1185300
X1198500
X1180500
X1182100Y254400
X1198400Y254100
X1182000Y248200
X1198300Y247500
X1182400Y241200
X1198900Y241100
X1188900Y234300
X1193700
X1184700
X1197900
X1199300Y215700
X1180601
X1185300
X1194500
X1190300
X1214800
X1203800
X1208800
X1203200Y234300
X1212900
X1207400
X1203100Y241100
X1207900
X1207300Y247500
X1202500
X1202600Y254100
X1207400
X1214000Y261500
X1208000
X1203800
X1210500Y280000
X1201000
X1205500
X1237000Y292000
X1232000
X1227000Y285500
Y279000
X1229000Y252000
X1234000
X1228800Y246600
X1239800
X1233800
X1228900Y240700
X1233900
X1239900
X1234000Y235000
X1228500
X1229000Y210500
X1226500Y201500
Y194500
X1232000
X1237000
X1252500
X1257500
X1244500
X1247500Y209000
X1242500
X1245000Y235000
X1256000
X1240000
X1250000
X1249900Y240700
X1255900
X1244900
X1249800Y246600
X1255800
X1244800
X1240000Y252000
X1250000
X1256000
X1245000
X1242000Y279000
X1247000
X1244500Y292000
X1252000
X1257000
X1262500Y286000
Y279500
X1262000Y252000
X1262500Y235000
X1263000Y210307
Y202000
X1262500Y194500
X1326250Y669550
X1332683Y248809
X1328317Y246291
X1332683Y244609
X1328356Y242091
X1332683Y240409
X1328411Y237679
X1327841Y228639
X1327782Y221579
Y215579
Y207579
Y200579
Y192579
X1351545Y198575
Y202879
X1351525Y207104
X1355944Y210313
X1349639Y211374
X1351954Y215268
X1351899Y219598
X1349298Y223737
X1355644Y223881
X1351777Y227823
X1351668Y232125
X1350987Y236754
X1354989Y239016
X1350950Y241000
Y246100
X1355050Y247300
X1372000Y249500
Y245300
Y240500
X1375359Y230110
X1360644Y223881
X1367042Y223895
X1375196Y217203
X1360844Y210366
X1366672Y210312
X1378500Y198000
X1374000Y196700
X1378115Y193344
X1374000Y192500
X1378115Y189144
X1374000Y188300
X1382500Y188000
Y193500
T06
X514309Y-315
Y52087
X547773Y106457
X530057
X591080
X573364
X557616Y52087
Y-315
X600923
X644230
Y52087
X600923
X616671Y106457
X634388
X659978
X677695
X687537Y52087
Y-315
X1116671
Y52087
X1132419Y106457
X1193442
X1175726
X1150135
X1159978Y52087
Y-315
X1203285
X1246592
Y52087
X1203285
X1219033Y106457
X1236750
X1262340
X1280057
X1289899Y52087
Y-315
T07
X476614Y157493
Y162493
Y167493
T08
X911616Y5908
X919486
X927361
X935236
X943111
X950986
X958856
Y13778
X950986
X943111
X935236
X927361
X919486
X911616
T09
X41603Y177598
X49595
X57587
X65579
X73571
X81563
X85599Y187598
X77607
X69615
X53551
X45559
X37567
T10
X134251Y153543
X144094
X151968
X161811
T11
X183900Y274372
X193900
X203900
X213900
X292500Y207200
X302500
X312500
X326200
X336200
X346200
X465485Y200680
Y190680
Y180680
X488462Y180761
Y190761
Y200761
X501742Y215594
X511742
X521742
X531742
X752300Y16200
X762300
X772300
X785300Y16100
X795300
X805300
X819291Y265354
Y285354
X1075197Y112126
Y92126
X1323195Y161642
Y179358
X1348785
Y161642
T12
X473231Y235560
X487404Y255245
X473231Y274930
T13
X31977Y116614
Y126614
X91189Y116614
Y126614
Y136614
T14
X26977Y151614
X96189
T15
X535962Y37520
X579269
X622577
X665884
X1138324
X1181631
X1224939
X1268246
T16
X122165Y142874
X173897
T17
X336417Y21260
X293110Y55906
X336417Y90551
X789850Y283464
Y236220
X1333661Y55906
X1376968Y21260
Y90551
T18
X1360630Y135826
Y801181
X39370
T19
X54378Y237402
T20
X1301120Y173278
Y183908
X116790Y252362
X92990
T21
X1027722Y-9125
X1054494
T22
X526215Y184000
X565585
T23
X700Y19100
X16200Y120100
X27200Y821800
X33800Y872600
X1389800Y879000
X1373200Y823500
X1384200Y122800
X1415100Y-36700
T24
X42587Y151614
X80579
M30
